FILE_TYPE = CONNECTIVITY;
{Allegro Design Entry HDL 17.4-2019 S026 (4007227) 1/17/2022}
"PAGE_NUMBER" = 22;
0"NC";
1"GMI_CPU0_G0_CPU1_G2_TX_DN<15:0>";
2"GMI_CPU0_G0_CPU1_G2_TX_DP<15:0>";
3"GMI_CPU0_G1_CPU1_G3_TX_DN<15:0>";
4"GMI_CPU0_G1_CPU1_G3_TX_DP<15:0>";
5"GMI_CPU1_G2_CPU0_G0_TX_DN<15:0>";
6"GMI_CPU1_G2_CPU0_G0_TX_DP<15:0>";
7"GMI_CPU1_G3_CPU0_G1_TX_DP<15:0>";
8"GMI_CPU1_G3_CPU0_G1_TX_DN<15:0>";
9"GMI_CPU1_G2_CPU0_G0_TX_DP<7>";
10"GMI_CPU1_G3_CPU0_G1_TX_DN<7>";
11"GMI_CPU1_G3_CPU0_G1_TX_DN<6>";
12"GMI_CPU1_G3_CPU0_G1_TX_DN<5>";
13"GMI_CPU1_G3_CPU0_G1_TX_DP<7>";
14"GMI_CPU1_G3_CPU0_G1_TX_DN<4>";
15"GMI_CPU1_G3_CPU0_G1_TX_DP<6>";
16"GMI_CPU1_G3_CPU0_G1_TX_DN<3>";
17"GMI_CPU1_G3_CPU0_G1_TX_DP<5>";
18"GMI_CPU1_G3_CPU0_G1_TX_DN<2>";
19"GMI_CPU1_G3_CPU0_G1_TX_DP<4>";
20"GMI_CPU1_G3_CPU0_G1_TX_DN<1>";
21"GMI_CPU1_G3_CPU0_G1_TX_DP<3>";
22"GMI_CPU1_G3_CPU0_G1_TX_DN<0>";
23"GMI_CPU1_G3_CPU0_G1_TX_DP<2>";
24"GMI_CPU1_G3_CPU0_G1_TX_DP<1>";
25"GMI_CPU1_G3_CPU0_G1_TX_DP<0>";
26"GMI_CPU1_G3_CPU0_G1_TX_DN<8>";
27"GMI_CPU1_G3_CPU0_G1_TX_DN<9>";
28"GMI_CPU1_G3_CPU0_G1_TX_DN<10>";
29"GMI_CPU1_G3_CPU0_G1_TX_DN<11>";
30"GMI_CPU1_G3_CPU0_G1_TX_DN<12>";
31"GMI_CPU1_G3_CPU0_G1_TX_DN<13>";
32"GMI_CPU1_G3_CPU0_G1_TX_DN<14>";
33"GMI_CPU1_G3_CPU0_G1_TX_DN<15>";
34"GMI_CPU1_G3_CPU0_G1_TX_DP<8>";
35"GMI_CPU1_G3_CPU0_G1_TX_DP<9>";
36"GMI_CPU1_G3_CPU0_G1_TX_DP<10>";
37"GMI_CPU1_G3_CPU0_G1_TX_DP<11>";
38"GMI_CPU1_G3_CPU0_G1_TX_DP<12>";
39"GMI_CPU1_G3_CPU0_G1_TX_DP<13>";
40"GMI_CPU1_G3_CPU0_G1_TX_DP<14>";
41"GMI_CPU1_G3_CPU0_G1_TX_DP<15>";
42"GMI_CPU1_G2_CPU0_G0_TX_DP<15>";
43"GMI_CPU1_G2_CPU0_G0_TX_DP<14>";
44"GMI_CPU1_G2_CPU0_G0_TX_DP<13>";
45"GMI_CPU1_G2_CPU0_G0_TX_DP<12>";
46"GMI_CPU1_G2_CPU0_G0_TX_DP<11>";
47"GMI_CPU1_G2_CPU0_G0_TX_DP<10>";
48"GMI_CPU1_G2_CPU0_G0_TX_DP<9>";
49"GMI_CPU1_G2_CPU0_G0_TX_DP<8>";
50"GMI_CPU1_G2_CPU0_G0_TX_DP<6>";
51"GMI_CPU1_G2_CPU0_G0_TX_DP<5>";
52"GMI_CPU1_G2_CPU0_G0_TX_DP<4>";
53"GMI_CPU1_G2_CPU0_G0_TX_DP<3>";
54"GMI_CPU1_G2_CPU0_G0_TX_DP<2>";
55"GMI_CPU1_G2_CPU0_G0_TX_DP<1>";
56"GMI_CPU1_G2_CPU0_G0_TX_DP<0>";
57"GMI_CPU1_G2_CPU0_G0_TX_DN<15>";
58"GMI_CPU1_G2_CPU0_G0_TX_DN<14>";
59"GMI_CPU1_G2_CPU0_G0_TX_DN<13>";
60"GMI_CPU1_G2_CPU0_G0_TX_DN<12>";
61"GMI_CPU1_G2_CPU0_G0_TX_DN<11>";
62"GMI_CPU1_G2_CPU0_G0_TX_DN<10>";
63"GMI_CPU1_G2_CPU0_G0_TX_DN<9>";
64"GMI_CPU1_G2_CPU0_G0_TX_DN<8>";
65"GMI_CPU1_G2_CPU0_G0_TX_DN<7>";
66"GMI_CPU1_G2_CPU0_G0_TX_DN<6>";
67"GMI_CPU1_G2_CPU0_G0_TX_DN<5>";
68"GMI_CPU1_G2_CPU0_G0_TX_DN<4>";
69"GMI_CPU1_G2_CPU0_G0_TX_DN<3>";
70"GMI_CPU1_G2_CPU0_G0_TX_DN<2>";
71"GMI_CPU1_G2_CPU0_G0_TX_DN<1>";
72"GMI_CPU1_G2_CPU0_G0_TX_DN<0>";
73"GMI_CPU0_G1_CPU1_G3_TX_DP<15>";
74"GMI_CPU0_G1_CPU1_G3_TX_DP<10>";
75"GMI_CPU0_G1_CPU1_G3_TX_DP<11>";
76"GMI_CPU0_G1_CPU1_G3_TX_DP<12>";
77"GMI_CPU0_G1_CPU1_G3_TX_DP<13>";
78"GMI_CPU0_G1_CPU1_G3_TX_DP<14>";
79"GMI_CPU0_G1_CPU1_G3_TX_DN<9>";
80"GMI_CPU0_G1_CPU1_G3_TX_DN<10>";
81"GMI_CPU0_G1_CPU1_G3_TX_DN<11>";
82"GMI_CPU0_G1_CPU1_G3_TX_DN<12>";
83"GMI_CPU0_G1_CPU1_G3_TX_DN<13>";
84"GMI_CPU0_G1_CPU1_G3_TX_DN<14>";
85"GMI_CPU0_G1_CPU1_G3_TX_DN<15>";
86"GMI_CPU0_G1_CPU1_G3_TX_DP<7>";
87"GMI_CPU0_G1_CPU1_G3_TX_DP<6>";
88"GMI_CPU0_G1_CPU1_G3_TX_DP<5>";
89"GMI_CPU0_G1_CPU1_G3_TX_DP<4>";
90"GMI_CPU0_G1_CPU1_G3_TX_DP<8>";
91"GMI_CPU0_G1_CPU1_G3_TX_DP<9>";
92"GMI_CPU0_G1_CPU1_G3_TX_DP<3>";
93"GMI_CPU0_G1_CPU1_G3_TX_DP<2>";
94"GMI_CPU0_G1_CPU1_G3_TX_DP<1>";
95"GMI_CPU0_G1_CPU1_G3_TX_DP<0>";
96"GMI_CPU0_G1_CPU1_G3_TX_DN<7>";
97"GMI_CPU0_G1_CPU1_G3_TX_DN<6>";
98"GMI_CPU0_G1_CPU1_G3_TX_DN<5>";
99"GMI_CPU0_G1_CPU1_G3_TX_DN<4>";
100"GMI_CPU0_G1_CPU1_G3_TX_DN<3>";
101"GMI_CPU0_G1_CPU1_G3_TX_DN<2>";
102"GMI_CPU0_G1_CPU1_G3_TX_DN<1>";
103"GMI_CPU0_G1_CPU1_G3_TX_DN<0>";
104"GMI_CPU0_G1_CPU1_G3_TX_DN<8>";
105"GMI_CPU0_G0_CPU1_G2_TX_DP<15>";
106"GMI_CPU0_G0_CPU1_G2_TX_DP<14>";
107"GMI_CPU0_G0_CPU1_G2_TX_DP<13>";
108"GMI_CPU0_G0_CPU1_G2_TX_DP<12>";
109"GMI_CPU0_G0_CPU1_G2_TX_DP<11>";
110"GMI_CPU0_G0_CPU1_G2_TX_DP<10>";
111"GMI_CPU0_G0_CPU1_G2_TX_DP<9>";
112"GMI_CPU0_G0_CPU1_G2_TX_DP<8>";
113"GMI_CPU0_G0_CPU1_G2_TX_DP<7>";
114"GMI_CPU0_G0_CPU1_G2_TX_DP<6>";
115"GMI_CPU0_G0_CPU1_G2_TX_DP<5>";
116"GMI_CPU0_G0_CPU1_G2_TX_DP<4>";
117"GMI_CPU0_G0_CPU1_G2_TX_DP<3>";
118"GMI_CPU0_G0_CPU1_G2_TX_DP<2>";
119"GMI_CPU0_G0_CPU1_G2_TX_DP<1>";
120"GMI_CPU0_G0_CPU1_G2_TX_DP<0>";
121"GMI_CPU0_G0_CPU1_G2_TX_DN<15>";
122"GMI_CPU0_G0_CPU1_G2_TX_DN<14>";
123"GMI_CPU0_G0_CPU1_G2_TX_DN<13>";
124"GMI_CPU0_G0_CPU1_G2_TX_DN<12>";
125"GMI_CPU0_G0_CPU1_G2_TX_DN<11>";
126"GMI_CPU0_G0_CPU1_G2_TX_DN<10>";
127"GMI_CPU0_G0_CPU1_G2_TX_DN<9>";
128"GMI_CPU0_G0_CPU1_G2_TX_DN<8>";
129"GMI_CPU0_G0_CPU1_G2_TX_DN<7>";
130"GMI_CPU0_G0_CPU1_G2_TX_DN<6>";
131"GMI_CPU0_G0_CPU1_G2_TX_DN<5>";
132"GMI_CPU0_G0_CPU1_G2_TX_DN<4>";
133"GMI_CPU0_G0_CPU1_G2_TX_DN<3>";
134"GMI_CPU0_G0_CPU1_G2_TX_DN<2>";
135"GMI_CPU0_G0_CPU1_G2_TX_DN<1>";
136"GMI_CPU0_G0_CPU1_G2_TX_DN<0>";
%"GENOA_SP5"
"11","(-4775,4925)","0","pure_quanta","I207";
;
LOCATION"U25"
$SEC"11"
CDS_SEC"11"
PART_TYPE"SMLF"
MATERIAL"IO"
VALUE"SOCKET6096_13568-001"
CDS_LIB"pure_quanta"
NEEDS_NO_SIZE"TRUE"
CDS_LMAN_SYM_OUTLINE"-1100,950,1100,-950"
PART_NUMBER"DGA^6000030";
"G0_TXP15"
$PN"AE52"105;
"G0_TXP14"
$PN"AC52"106;
"G0_TXP13"
$PN"AG52"107;
"G0_TXP12"
$PN"AE49"108;
"G0_TXP11"
$PN"AC49"109;
"G0_TXP10"
$PN"AG49"110;
"G0_TXP9"
$PN"AE46"111;
"G0_TXP8"
$PN"AC46"112;
"G0_TXP7"
$PN"AG46"113;
"G0_TXP6"
$PN"AE43"114;
"G0_TXP5"
$PN"AC43"115;
"G0_TXP4"
$PN"AA43"116;
"G0_TXP3"
$PN"AG43"117;
"G0_TXP2"
$PN"AB40"118;
"G0_TXP1"
$PN"AD40"119;
"G0_TXP0"
$PN"AF40"120;
"G0_TXN15"
$PN"AE53"121;
"G0_TXN14"
$PN"AC53"122;
"G0_TXN13"
$PN"AG53"123;
"G0_TXN12"
$PN"AE50"124;
"G0_TXN11"
$PN"AC50"125;
"G0_TXN10"
$PN"AG50"126;
"G0_TXN9"
$PN"AE47"127;
"G0_TXN8"
$PN"AC47"128;
"G0_TXN7"
$PN"AG47"129;
"G0_TXN6"
$PN"AE44"130;
"G0_TXN5"
$PN"AC44"131;
"G0_TXN4"
$PN"AA44"132;
"G0_TXN3"
$PN"AG44"133;
"G0_TXN2"
$PN"AB41"134;
"G0_TXN1"
$PN"AD41"135;
"G0_TXN0"
$PN"AF41"136;
"G0_RXP15"
$PN"N53"42;
"G0_RXP14"
$PN"J53"43;
"G0_RXP13"
$PN"G53"44;
"G0_RXP12"
$PN"L53"45;
"G0_RXP11"
$PN"J50"46;
"G0_RXP10"
$PN"G50"47;
"G0_RXP9"
$PN"L50"48;
"G0_RXP8"
$PN"J47"49;
"G0_RXP7"
$PN"G47"9;
"G0_RXP6"
$PN"L47"50;
"G0_RXP5"
$PN"J44"51;
"G0_RXP4"
$PN"G44"52;
"G0_RXP3"
$PN"L44"53;
"G0_RXP2"
$PN"H41"54;
"G0_RXP1"
$PN"K41"55;
"G0_RXP0"
$PN"M41"56;
"G0_RXN15"
$PN"N52"57;
"G0_RXN14"
$PN"J52"58;
"G0_RXN13"
$PN"G52"59;
"G0_RXN12"
$PN"L52"60;
"G0_RXN11"
$PN"J49"61;
"G0_RXN10"
$PN"G49"62;
"G0_RXN9"
$PN"L49"63;
"G0_RXN8"
$PN"J46"64;
"G0_RXN7"
$PN"G46"65;
"G0_RXN6"
$PN"L46"66;
"G0_RXN5"
$PN"J43"67;
"G0_RXN4"
$PN"G43"68;
"G0_RXN3"
$PN"L43"69;
"G0_RXN2"
$PN"H40"70;
"G0_RXN1"
$PN"K40"71;
"G0_RXN0"
$PN"M40"72;
%"GENOA_SP5"
"12","(-4775,2200)","0","pure_quanta","I208";
;
LOCATION"U25"
$SEC"12"
CDS_SEC"12"
PART_TYPE"SMLF"
MATERIAL"IO"
VALUE"SOCKET6096_13568-001"
CDS_LIB"pure_quanta"
NEEDS_NO_SIZE"TRUE"
CDS_LMAN_SYM_OUTLINE"-1100,950,1100,-950"
PART_NUMBER"DGA^6000030";
"G1_RXN7"
$PN"N46"10;
"G1_RXN6"
$PN"U46"11;
"G1_RXN5"
$PN"R43"12;
"G1_RXP7"
$PN"N47"13;
"G1_TXN7"
$PN"AN47"96;
"G1_RXN4"
$PN"N43"14;
"G1_RXP6"
$PN"U47"15;
"G1_TXN6"
$PN"AL44"97;
"G1_RXN3"
$PN"U43"16;
"G1_RXP5"
$PN"R44"17;
"G1_TXN5"
$PN"AJ44"98;
"G1_TXP7"
$PN"AN46"86;
"G1_RXN2"
$PN"P40"18;
"G1_RXP4"
$PN"N44"19;
"G1_TXN4"
$PN"AN44"99;
"G1_TXP6"
$PN"AL43"87;
"G1_RXN1"
$PN"T40"20;
"G1_RXP3"
$PN"U44"21;
"G1_TXN3"
$PN"AK41"100;
"G1_TXP5"
$PN"AJ43"88;
"G1_RXN0"
$PN"V40"22;
"G1_RXP2"
$PN"P41"23;
"G1_TXN2"
$PN"AH41"101;
"G1_TXP4"
$PN"AN43"89;
"G1_RXP1"
$PN"T41"24;
"G1_TXN1"
$PN"AM41"102;
"G1_TXP3"
$PN"AK40"92;
"G1_RXP0"
$PN"V41"25;
"G1_TXN0"
$PN"AP41"103;
"G1_TXP2"
$PN"AH40"93;
"G1_TXP1"
$PN"AM40"94;
"G1_TXP0"
$PN"AP40"95;
"G1_RXN8"
$PN"R46"26;
"G1_RXN9"
$PN"W49"27;
"G1_RXN10"
$PN"N49"28;
"G1_RXN11"
$PN"R49"29;
"G1_RXN12"
$PN"U49"30;
"G1_RXN13"
$PN"W52"31;
"G1_RXN14"
$PN"R52"32;
"G1_RXN15"
$PN"U52"33;
"G1_RXP8"
$PN"R47"34;
"G1_RXP9"
$PN"W50"35;
"G1_RXP10"
$PN"N50"36;
"G1_RXP11"
$PN"R50"37;
"G1_RXP12"
$PN"U50"38;
"G1_RXP13"
$PN"W53"39;
"G1_RXP14"
$PN"R53"40;
"G1_RXP15"
$PN"U53"41;
"G1_TXN8"
$PN"AJ47"104;
"G1_TXN9"
$PN"AL47"79;
"G1_TXN10"
$PN"AN50"80;
"G1_TXN11"
$PN"AJ50"81;
"G1_TXN12"
$PN"AL50"82;
"G1_TXN13"
$PN"AN53"83;
"G1_TXN14"
$PN"AJ53"84;
"G1_TXN15"
$PN"AL53"85;
"G1_TXP8"
$PN"AJ46"90;
"G1_TXP9"
$PN"AL46"91;
"G1_TXP10"
$PN"AN49"74;
"G1_TXP11"
$PN"AJ49"75;
"G1_TXP12"
$PN"AL49"76;
"G1_TXP13"
$PN"AN52"77;
"G1_TXP14"
$PN"AJ52"78;
"G1_TXP15"
$PN"AL52"73;
%"TAP"
"6","(-3100,5675)","2","mstr_standard","I245";
;
BOM_COST"IO_SLOT"
CDS_LIB"mstr_standard"
ROOM"RISER1"
BODY_TYPE"PLUMBING"
HDL_TAP"TRUE";
"B \NAC \NWC"2;
"S \NAC"
BN"0"120;
%"TAP"
"6","(-2950,5625)","2","mstr_standard","I246";
;
BOM_COST"IO_SLOT"
CDS_LIB"mstr_standard"
ROOM"RISER1"
BODY_TYPE"PLUMBING"
HDL_TAP"TRUE";
"B \NAC \NWC"1;
"S \NAC"
BN"0"136;
%"TAP"
"6","(-2950,5525)","2","mstr_standard","I247";
;
BOM_COST"IO_SLOT"
CDS_LIB"mstr_standard"
ROOM"RISER1"
BODY_TYPE"PLUMBING"
HDL_TAP"TRUE";
"B \NAC \NWC"1;
"S \NAC"
BN"1"135;
%"TAP"
"6","(-2950,5425)","2","standard","I248";
;
CDS_LIB"standard"
BOM_COST"IO_SLOT"
ROOM"RISER1"
BODY_TYPE"PLUMBING"
HDL_TAP"TRUE";
"B \NAC \NWC"1;
"S \NAC"
BN"2"134;
%"TAP"
"6","(-3100,5475)","2","standard","I249";
;
CDS_LIB"standard"
BOM_COST"IO_SLOT"
ROOM"RISER1"
BODY_TYPE"PLUMBING"
HDL_TAP"TRUE";
"B \NAC \NWC"2;
"S \NAC"
BN"2"118;
%"TAP"
"6","(-3100,5575)","2","mstr_standard","I250";
;
CDS_LIB"mstr_standard"
BOM_COST"IO_SLOT"
ROOM"RISER1"
BODY_TYPE"PLUMBING"
HDL_TAP"TRUE";
"B \NAC \NWC"2;
"S \NAC"
BN"1"119;
%"TAP"
"6","(-2950,5325)","2","standard","I251";
;
CDS_LIB"standard"
BOM_COST"IO_SLOT"
ROOM"RISER1"
BODY_TYPE"PLUMBING"
HDL_TAP"TRUE";
"B \NAC \NWC"1;
"S \NAC"
BN"3"133;
%"TAP"
"6","(-2950,5225)","2","standard","I252";
;
CDS_LIB"standard"
BOM_COST"IO_SLOT"
ROOM"RISER1"
BODY_TYPE"PLUMBING"
HDL_TAP"TRUE";
"B \NAC \NWC"1;
"S \NAC"
BN"4"132;
%"TAP"
"6","(-2950,5125)","2","standard","I253";
;
CDS_LIB"standard"
BOM_COST"IO_SLOT"
ROOM"RISER1"
BODY_TYPE"PLUMBING"
HDL_TAP"TRUE";
"B \NAC \NWC"1;
"S \NAC"
BN"5"131;
%"TAP"
"6","(-3100,5275)","2","standard","I254";
;
BOM_COST"IO_SLOT"
CDS_LIB"standard"
ROOM"RISER1"
BODY_TYPE"PLUMBING"
HDL_TAP"TRUE";
"B \NAC \NWC"2;
"S \NAC"
BN"4"116;
%"TAP"
"6","(-3100,5175)","2","standard","I255";
;
BOM_COST"IO_SLOT"
CDS_LIB"standard"
ROOM"RISER1"
BODY_TYPE"PLUMBING"
HDL_TAP"TRUE";
"B \NAC \NWC"2;
"S \NAC"
BN"5"115;
%"TAP"
"6","(-3100,5375)","2","standard","I256";
;
BOM_COST"IO_SLOT"
CDS_LIB"standard"
ROOM"RISER1"
BODY_TYPE"PLUMBING"
HDL_TAP"TRUE";
"B \NAC \NWC"2;
"S \NAC"
BN"3"117;
%"TAP"
"6","(-2950,5025)","2","standard","I257";
;
CDS_LIB"standard"
BOM_COST"IO_SLOT"
ROOM"RISER1"
BODY_TYPE"PLUMBING"
HDL_TAP"TRUE";
"B \NAC \NWC"1;
"S \NAC"
BN"6"130;
%"TAP"
"6","(-2950,4925)","2","standard","I258";
;
CDS_LIB"standard"
BOM_COST"IO_SLOT"
ROOM"RISER1"
BODY_TYPE"PLUMBING"
HDL_TAP"TRUE";
"B \NAC \NWC"1;
"S \NAC"
BN"7"129;
%"TAP"
"6","(-3100,4875)","2","standard","I259";
;
BOM_COST"IO_SLOT"
CDS_LIB"standard"
ROOM"RISER1"
BODY_TYPE"PLUMBING"
HDL_TAP"TRUE";
"B \NAC \NWC"2;
"S \NAC"
BN"8"112;
%"TAP"
"6","(-3100,4975)","2","standard","I260";
;
BOM_COST"IO_SLOT"
CDS_LIB"standard"
ROOM"RISER1"
BODY_TYPE"PLUMBING"
HDL_TAP"TRUE";
"B \NAC \NWC"2;
"S \NAC"
BN"7"113;
%"TAP"
"6","(-3100,5075)","2","standard","I261";
;
BOM_COST"IO_SLOT"
CDS_LIB"standard"
ROOM"RISER1"
BODY_TYPE"PLUMBING"
HDL_TAP"TRUE";
"B \NAC \NWC"2;
"S \NAC"
BN"6"114;
%"TAP"
"6","(-2950,4825)","2","standard","I262";
;
CDS_LIB"standard"
BOM_COST"IO_SLOT"
ROOM"RISER1"
BODY_TYPE"PLUMBING"
HDL_TAP"TRUE";
"B \NAC \NWC"1;
"S \NAC"
BN"8"128;
%"TAP"
"6","(-2950,4725)","2","standard","I263";
;
CDS_LIB"standard"
BOM_COST"IO_SLOT"
ROOM"RISER1"
BODY_TYPE"PLUMBING"
HDL_TAP"TRUE";
"B \NAC \NWC"1;
"S \NAC"
BN"9"127;
%"TAP"
"6","(-2950,4625)","2","standard","I264";
;
CDS_LIB"standard"
BOM_COST"IO_SLOT"
ROOM"RISER1"
BODY_TYPE"PLUMBING"
HDL_TAP"TRUE";
"B \NAC \NWC"1;
"S \NAC"
BN"10"126;
%"TAP"
"6","(-3100,4675)","2","standard","I265";
;
BOM_COST"IO_SLOT"
CDS_LIB"standard"
ROOM"RISER1"
BODY_TYPE"PLUMBING"
HDL_TAP"TRUE";
"B \NAC \NWC"2;
"S \NAC"
BN"10"110;
%"TAP"
"6","(-3100,4775)","2","standard","I266";
;
BOM_COST"IO_SLOT"
CDS_LIB"standard"
ROOM"RISER1"
BODY_TYPE"PLUMBING"
HDL_TAP"TRUE";
"B \NAC \NWC"2;
"S \NAC"
BN"9"111;
%"TAP"
"6","(-2950,4525)","2","standard","I267";
;
CDS_LIB"standard"
BOM_COST"IO_SLOT"
ROOM"RISER1"
BODY_TYPE"PLUMBING"
HDL_TAP"TRUE";
"B \NAC \NWC"1;
"S \NAC"
BN"11"125;
%"TAP"
"6","(-2950,4425)","2","standard","I268";
;
CDS_LIB"standard"
BOM_COST"IO_SLOT"
ROOM"RISER1"
BODY_TYPE"PLUMBING"
HDL_TAP"TRUE";
"B \NAC \NWC"1;
"S \NAC"
BN"12"124;
%"TAP"
"6","(-3100,4375)","2","standard","I269";
;
BOM_COST"IO_SLOT"
CDS_LIB"standard"
ROOM"RISER1"
BODY_TYPE"PLUMBING"
HDL_TAP"TRUE";
"B \NAC \NWC"2;
"S \NAC"
BN"13"107;
%"TAP"
"6","(-3100,4475)","2","standard","I270";
;
BOM_COST"IO_SLOT"
CDS_LIB"standard"
ROOM"RISER1"
BODY_TYPE"PLUMBING"
HDL_TAP"TRUE";
"B \NAC \NWC"2;
"S \NAC"
BN"12"108;
%"TAP"
"6","(-3100,4575)","2","standard","I271";
;
BOM_COST"IO_SLOT"
CDS_LIB"standard"
ROOM"RISER1"
BODY_TYPE"PLUMBING"
HDL_TAP"TRUE";
"B \NAC \NWC"2;
"S \NAC"
BN"11"109;
%"TAP"
"6","(-2950,4225)","2","standard","I272";
;
BOM_COST"IO_SLOT"
CDS_LIB"standard"
ROOM"RISER1"
BODY_TYPE"PLUMBING"
HDL_TAP"TRUE";
"B \NAC \NWC"1;
"S \NAC"
BN"14"122;
%"TAP"
"6","(-2950,4125)","2","standard","I273";
;
CDS_LIB"standard"
BOM_COST"IO_SLOT"
ROOM"RISER1"
BODY_TYPE"PLUMBING"
HDL_TAP"TRUE";
"B \NAC \NWC"1;
"S \NAC"
BN"15"121;
%"TAP"
"6","(-2950,4325)","2","standard","I274";
;
CDS_LIB"standard"
BOM_COST"IO_SLOT"
ROOM"RISER1"
BODY_TYPE"PLUMBING"
HDL_TAP"TRUE";
"B \NAC \NWC"1;
"S \NAC"
BN"13"123;
%"TAP"
"6","(-3100,4175)","2","standard","I275";
;
BOM_COST"IO_SLOT"
CDS_LIB"standard"
ROOM"RISER1"
BODY_TYPE"PLUMBING"
HDL_TAP"TRUE";
"B \NAC \NWC"2;
"S \NAC"
BN"15"105;
%"TAP"
"6","(-3100,4275)","2","standard","I276";
;
BOM_COST"IO_SLOT"
CDS_LIB"standard"
ROOM"RISER1"
BODY_TYPE"PLUMBING"
HDL_TAP"TRUE";
"B \NAC \NWC"2;
"S \NAC"
BN"14"106;
%"TAP"
"6","(-6525,5675)","0","mstr_standard","I277";
;
CDS_LIB"mstr_standard"
BODY_TYPE"PLUMBING"
HDL_TAP"TRUE";
"B \NAC \NWC"6;
"S \NAC"
BN"0"56;
%"TAP"
"6","(-6525,5575)","0","mstr_standard","I278";
;
CDS_LIB"mstr_standard"
BODY_TYPE"PLUMBING"
HDL_TAP"TRUE";
"B \NAC \NWC"6;
"S \NAC"
BN"1"55;
%"TAP"
"6","(-6525,5475)","0","mstr_standard","I279";
;
CDS_LIB"mstr_standard"
BODY_TYPE"PLUMBING"
HDL_TAP"TRUE";
"B \NAC \NWC"6;
"S \NAC"
BN"2"54;
%"TAP"
"6","(-6675,5625)","0","mstr_standard","I280";
;
CDS_LIB"mstr_standard"
BODY_TYPE"PLUMBING"
HDL_TAP"TRUE";
"B \NAC \NWC"5;
"S \NAC"
BN"0"72;
%"TAP"
"6","(-6675,5525)","0","mstr_standard","I281";
;
CDS_LIB"mstr_standard"
BODY_TYPE"PLUMBING"
HDL_TAP"TRUE";
"B \NAC \NWC"5;
"S \NAC"
BN"1"71;
%"TAP"
"6","(-6675,5425)","0","standard","I282";
;
CDS_LIB"standard"
BODY_TYPE"PLUMBING"
HDL_TAP"TRUE";
"B \NAC \NWC"5;
"S \NAC"
BN"2"70;
%"TAP"
"6","(-6525,5275)","0","standard","I283";
;
CDS_LIB"standard"
BODY_TYPE"PLUMBING"
HDL_TAP"TRUE";
"B \NAC \NWC"6;
"S \NAC"
BN"4"52;
%"TAP"
"6","(-6525,5375)","0","standard","I284";
;
CDS_LIB"standard"
BODY_TYPE"PLUMBING"
HDL_TAP"TRUE";
"B \NAC \NWC"6;
"S \NAC"
BN"3"53;
%"TAP"
"6","(-6525,5175)","0","standard","I285";
;
CDS_LIB"standard"
BODY_TYPE"PLUMBING"
HDL_TAP"TRUE";
"B \NAC \NWC"6;
"S \NAC"
BN"5"51;
%"TAP"
"6","(-6675,5325)","0","standard","I286";
;
CDS_LIB"standard"
BODY_TYPE"PLUMBING"
HDL_TAP"TRUE";
"B \NAC \NWC"5;
"S \NAC"
BN"3"69;
%"TAP"
"6","(-6675,5225)","0","standard","I287";
;
CDS_LIB"standard"
BODY_TYPE"PLUMBING"
HDL_TAP"TRUE";
"B \NAC \NWC"5;
"S \NAC"
BN"4"68;
%"TAP"
"6","(-6675,5125)","0","standard","I288";
;
CDS_LIB"standard"
BODY_TYPE"PLUMBING"
HDL_TAP"TRUE";
"B \NAC \NWC"5;
"S \NAC"
BN"5"67;
%"TAP"
"6","(-6525,5075)","0","standard","I289";
;
CDS_LIB"standard"
BODY_TYPE"PLUMBING"
HDL_TAP"TRUE";
"B \NAC \NWC"6;
"S \NAC"
BN"6"50;
%"TAP"
"6","(-6525,4975)","0","standard","I290";
;
CDS_LIB"standard"
BODY_TYPE"PLUMBING"
HDL_TAP"TRUE";
"B \NAC \NWC"6;
"S \NAC"
BN"7"9;
%"TAP"
"6","(-6525,4875)","0","standard","I291";
;
CDS_LIB"standard"
BODY_TYPE"PLUMBING"
HDL_TAP"TRUE";
"B \NAC \NWC"6;
"S \NAC"
BN"8"49;
%"TAP"
"6","(-6675,5025)","0","standard","I292";
;
CDS_LIB"standard"
BODY_TYPE"PLUMBING"
HDL_TAP"TRUE";
"B \NAC \NWC"5;
"S \NAC"
BN"6"66;
%"TAP"
"6","(-6675,4925)","0","standard","I293";
;
CDS_LIB"standard"
BODY_TYPE"PLUMBING"
HDL_TAP"TRUE";
"B \NAC \NWC"5;
"S \NAC"
BN"7"65;
%"TAP"
"6","(-6525,4775)","0","standard","I294";
;
CDS_LIB"standard"
BODY_TYPE"PLUMBING"
HDL_TAP"TRUE";
"B \NAC \NWC"6;
"S \NAC"
BN"9"48;
%"TAP"
"6","(-6525,4675)","0","standard","I295";
;
CDS_LIB"standard"
BODY_TYPE"PLUMBING"
HDL_TAP"TRUE";
"B \NAC \NWC"6;
"S \NAC"
BN"10"47;
%"TAP"
"6","(-6675,4825)","0","standard","I296";
;
CDS_LIB"standard"
BODY_TYPE"PLUMBING"
HDL_TAP"TRUE";
"B \NAC \NWC"5;
"S \NAC"
BN"8"64;
%"TAP"
"6","(-6675,4725)","0","standard","I297";
;
CDS_LIB"standard"
BODY_TYPE"PLUMBING"
HDL_TAP"TRUE";
"B \NAC \NWC"5;
"S \NAC"
BN"9"63;
%"TAP"
"6","(-6675,4625)","0","standard","I298";
;
CDS_LIB"standard"
BODY_TYPE"PLUMBING"
HDL_TAP"TRUE";
"B \NAC \NWC"5;
"S \NAC"
BN"10"62;
%"TAP"
"6","(-6525,4575)","0","standard","I299";
;
CDS_LIB"standard"
BODY_TYPE"PLUMBING"
HDL_TAP"TRUE";
"B \NAC \NWC"6;
"S \NAC"
BN"11"46;
%"TAP"
"6","(-6525,4475)","0","standard","I300";
;
CDS_LIB"standard"
BODY_TYPE"PLUMBING"
HDL_TAP"TRUE";
"B \NAC \NWC"6;
"S \NAC"
BN"12"45;
%"TAP"
"6","(-6525,4375)","0","standard","I301";
;
CDS_LIB"standard"
BODY_TYPE"PLUMBING"
HDL_TAP"TRUE";
"B \NAC \NWC"6;
"S \NAC"
BN"13"44;
%"TAP"
"6","(-6675,4525)","0","standard","I302";
;
CDS_LIB"standard"
BODY_TYPE"PLUMBING"
HDL_TAP"TRUE";
"B \NAC \NWC"5;
"S \NAC"
BN"11"61;
%"TAP"
"6","(-6675,4425)","0","standard","I303";
;
CDS_LIB"standard"
BODY_TYPE"PLUMBING"
HDL_TAP"TRUE";
"B \NAC \NWC"5;
"S \NAC"
BN"12"60;
%"TAP"
"6","(-6525,4275)","0","standard","I304";
;
CDS_LIB"standard"
BODY_TYPE"PLUMBING"
HDL_TAP"TRUE";
"B \NAC \NWC"6;
"S \NAC"
BN"14"43;
%"TAP"
"6","(-6525,4175)","0","standard","I305";
;
CDS_LIB"standard"
BODY_TYPE"PLUMBING"
HDL_TAP"TRUE";
"B \NAC \NWC"6;
"S \NAC"
BN"15"42;
%"TAP"
"6","(-6675,4325)","0","standard","I306";
;
CDS_LIB"standard"
BODY_TYPE"PLUMBING"
HDL_TAP"TRUE";
"B \NAC \NWC"5;
"S \NAC"
BN"13"59;
%"TAP"
"6","(-6675,4225)","0","standard","I307";
;
CDS_LIB"standard"
BODY_TYPE"PLUMBING"
HDL_TAP"TRUE";
"B \NAC \NWC"5;
"S \NAC"
BN"14"58;
%"TAP"
"6","(-6675,4125)","0","standard","I308";
;
CDS_LIB"standard"
BODY_TYPE"PLUMBING"
HDL_TAP"TRUE";
"B \NAC \NWC"5;
"S \NAC"
BN"15"57;
%"TAP"
"6","(-2950,2900)","2","mstr_standard","I313";
;
CDS_LIB"mstr_standard"
BOM_COST"IO_SLOT"
ROOM"RISER1"
BODY_TYPE"PLUMBING"
HDL_TAP"TRUE";
"B \NAC \NWC"3;
"S \NAC"
BN"0"103;
%"TAP"
"6","(-3100,2850)","2","mstr_standard","I314";
;
CDS_LIB"mstr_standard"
BOM_COST"IO_SLOT"
ROOM"RISER1"
BODY_TYPE"PLUMBING"
HDL_TAP"TRUE";
"B \NAC \NWC"4;
"S \NAC"
BN"1"94;
%"TAP"
"6","(-3100,2950)","2","mstr_standard","I315";
;
BOM_COST"IO_SLOT"
CDS_LIB"mstr_standard"
ROOM"RISER1"
BODY_TYPE"PLUMBING"
HDL_TAP"TRUE";
"B \NAC \NWC"4;
"S \NAC"
BN"0"95;
%"TAP"
"6","(-2950,2800)","2","mstr_standard","I316";
;
BOM_COST"IO_SLOT"
CDS_LIB"mstr_standard"
ROOM"RISER1"
BODY_TYPE"PLUMBING"
HDL_TAP"TRUE";
"B \NAC \NWC"3;
"S \NAC"
BN"1"102;
%"TAP"
"6","(-2950,2700)","2","standard","I317";
;
BOM_COST"IO_SLOT"
CDS_LIB"standard"
ROOM"RISER1"
BODY_TYPE"PLUMBING"
HDL_TAP"TRUE";
"B \NAC \NWC"3;
"S \NAC"
BN"2"101;
%"TAP"
"6","(-2950,2600)","2","standard","I318";
;
BOM_COST"IO_SLOT"
CDS_LIB"standard"
ROOM"RISER1"
BODY_TYPE"PLUMBING"
HDL_TAP"TRUE";
"B \NAC \NWC"3;
"S \NAC"
BN"3"100;
%"TAP"
"6","(-3100,2650)","2","standard","I319";
;
CDS_LIB"standard"
BOM_COST"IO_SLOT"
ROOM"RISER1"
BODY_TYPE"PLUMBING"
HDL_TAP"TRUE";
"B \NAC \NWC"4;
"S \NAC"
BN"3"92;
%"TAP"
"6","(-3100,2750)","2","standard","I320";
;
CDS_LIB"standard"
BOM_COST"IO_SLOT"
ROOM"RISER1"
BODY_TYPE"PLUMBING"
HDL_TAP"TRUE";
"B \NAC \NWC"4;
"S \NAC"
BN"2"93;
%"TAP"
"6","(-2950,2400)","2","standard","I321";
;
BOM_COST"IO_SLOT"
CDS_LIB"standard"
ROOM"RISER1"
BODY_TYPE"PLUMBING"
HDL_TAP"TRUE";
"B \NAC \NWC"3;
"S \NAC"
BN"5"98;
%"TAP"
"6","(-2950,2500)","2","standard","I322";
;
BOM_COST"IO_SLOT"
CDS_LIB"standard"
ROOM"RISER1"
BODY_TYPE"PLUMBING"
HDL_TAP"TRUE";
"B \NAC \NWC"3;
"S \NAC"
BN"4"99;
%"TAP"
"6","(-3100,2350)","2","standard","I323";
;
CDS_LIB"standard"
BOM_COST"IO_SLOT"
ROOM"RISER1"
BODY_TYPE"PLUMBING"
HDL_TAP"TRUE";
"B \NAC \NWC"4;
"S \NAC"
BN"6"87;
%"TAP"
"6","(-3100,2450)","2","standard","I324";
;
CDS_LIB"standard"
BOM_COST"IO_SLOT"
ROOM"RISER1"
BODY_TYPE"PLUMBING"
HDL_TAP"TRUE";
"B \NAC \NWC"4;
"S \NAC"
BN"5"88;
%"TAP"
"6","(-3100,2550)","2","standard","I325";
;
CDS_LIB"standard"
BOM_COST"IO_SLOT"
ROOM"RISER1"
BODY_TYPE"PLUMBING"
HDL_TAP"TRUE";
"B \NAC \NWC"4;
"S \NAC"
BN"4"89;
%"TAP"
"6","(-2950,2200)","2","standard","I326";
;
BOM_COST"IO_SLOT"
CDS_LIB"standard"
ROOM"RISER1"
BODY_TYPE"PLUMBING"
HDL_TAP"TRUE";
"B \NAC \NWC"3;
"S \NAC"
BN"7"96;
%"TAP"
"6","(-2950,2300)","2","standard","I327";
;
BOM_COST"IO_SLOT"
CDS_LIB"standard"
ROOM"RISER1"
BODY_TYPE"PLUMBING"
HDL_TAP"TRUE";
"B \NAC \NWC"3;
"S \NAC"
BN"6"97;
%"TAP"
"6","(-2950,2100)","2","standard","I328";
;
BOM_COST"IO_SLOT"
CDS_LIB"standard"
ROOM"RISER1"
BODY_TYPE"PLUMBING"
HDL_TAP"TRUE";
"B \NAC \NWC"3;
"S \NAC"
BN"8"104;
%"TAP"
"6","(-3100,2150)","2","standard","I329";
;
CDS_LIB"standard"
BOM_COST"IO_SLOT"
ROOM"RISER1"
BODY_TYPE"PLUMBING"
HDL_TAP"TRUE";
"B \NAC \NWC"4;
"S \NAC"
BN"8"90;
%"TAP"
"6","(-3100,2050)","2","standard","I330";
;
CDS_LIB"standard"
BOM_COST"IO_SLOT"
ROOM"RISER1"
BODY_TYPE"PLUMBING"
HDL_TAP"TRUE";
"B \NAC \NWC"4;
"S \NAC"
BN"9"91;
%"TAP"
"6","(-3100,2250)","2","standard","I331";
;
CDS_LIB"standard"
BOM_COST"IO_SLOT"
ROOM"RISER1"
BODY_TYPE"PLUMBING"
HDL_TAP"TRUE";
"B \NAC \NWC"4;
"S \NAC"
BN"7"86;
%"TAP"
"6","(-2950,2000)","2","standard","I332";
;
BOM_COST"IO_SLOT"
CDS_LIB"standard"
ROOM"RISER1"
BODY_TYPE"PLUMBING"
HDL_TAP"TRUE";
"B \NAC \NWC"3;
"S \NAC"
BN"9"79;
%"TAP"
"6","(-2950,1900)","2","standard","I333";
;
BOM_COST"IO_SLOT"
CDS_LIB"standard"
ROOM"RISER1"
BODY_TYPE"PLUMBING"
HDL_TAP"TRUE";
"B \NAC \NWC"3;
"S \NAC"
BN"10"80;
%"TAP"
"6","(-2950,1800)","2","standard","I334";
;
BOM_COST"IO_SLOT"
CDS_LIB"standard"
ROOM"RISER1"
BODY_TYPE"PLUMBING"
HDL_TAP"TRUE";
"B \NAC \NWC"3;
"S \NAC"
BN"11"81;
%"TAP"
"6","(-3100,1850)","2","standard","I335";
;
CDS_LIB"standard"
BOM_COST"IO_SLOT"
ROOM"RISER1"
BODY_TYPE"PLUMBING"
HDL_TAP"TRUE";
"B \NAC \NWC"4;
"S \NAC"
BN"11"75;
%"TAP"
"6","(-3100,1950)","2","standard","I336";
;
CDS_LIB"standard"
BOM_COST"IO_SLOT"
ROOM"RISER1"
BODY_TYPE"PLUMBING"
HDL_TAP"TRUE";
"B \NAC \NWC"4;
"S \NAC"
BN"10"74;
%"TAP"
"6","(-2950,1700)","2","standard","I337";
;
BOM_COST"IO_SLOT"
CDS_LIB"standard"
ROOM"RISER1"
BODY_TYPE"PLUMBING"
HDL_TAP"TRUE";
"B \NAC \NWC"3;
"S \NAC"
BN"12"82;
%"TAP"
"6","(-2950,1600)","2","standard","I338";
;
BOM_COST"IO_SLOT"
CDS_LIB"standard"
ROOM"RISER1"
BODY_TYPE"PLUMBING"
HDL_TAP"TRUE";
"B \NAC \NWC"3;
"S \NAC"
BN"13"83;
%"TAP"
"6","(-3100,1550)","2","standard","I339";
;
CDS_LIB"standard"
BOM_COST"IO_SLOT"
ROOM"RISER1"
BODY_TYPE"PLUMBING"
HDL_TAP"TRUE";
"B \NAC \NWC"4;
"S \NAC"
BN"14"78;
%"TAP"
"6","(-3100,1650)","2","standard","I340";
;
CDS_LIB"standard"
BOM_COST"IO_SLOT"
ROOM"RISER1"
BODY_TYPE"PLUMBING"
HDL_TAP"TRUE";
"B \NAC \NWC"4;
"S \NAC"
BN"13"77;
%"TAP"
"6","(-3100,1750)","2","standard","I341";
;
CDS_LIB"standard"
BOM_COST"IO_SLOT"
ROOM"RISER1"
BODY_TYPE"PLUMBING"
HDL_TAP"TRUE";
"B \NAC \NWC"4;
"S \NAC"
BN"12"76;
%"TAP"
"6","(-2950,1400)","2","standard","I342";
;
BOM_COST"IO_SLOT"
CDS_LIB"standard"
ROOM"RISER1"
BODY_TYPE"PLUMBING"
HDL_TAP"TRUE";
"B \NAC \NWC"3;
"S \NAC"
BN"15"85;
%"TAP"
"6","(-2950,1500)","2","standard","I343";
;
BOM_COST"IO_SLOT"
CDS_LIB"standard"
ROOM"RISER1"
BODY_TYPE"PLUMBING"
HDL_TAP"TRUE";
"B \NAC \NWC"3;
"S \NAC"
BN"14"84;
%"TAP"
"6","(-3100,1450)","2","standard","I344";
;
CDS_LIB"standard"
BOM_COST"IO_SLOT"
ROOM"RISER1"
BODY_TYPE"PLUMBING"
HDL_TAP"TRUE";
"B \NAC \NWC"4;
"S \NAC"
BN"15"73;
%"TAP"
"6","(-6525,2950)","0","mstr_standard","I345";
;
CDS_LIB"mstr_standard"
BODY_TYPE"PLUMBING"
HDL_TAP"TRUE";
"B \NAC \NWC"7;
"S \NAC"
BN"0"25;
%"TAP"
"6","(-6525,2850)","0","mstr_standard","I346";
;
CDS_LIB"mstr_standard"
BODY_TYPE"PLUMBING"
HDL_TAP"TRUE";
"B \NAC \NWC"7;
"S \NAC"
BN"1"24;
%"TAP"
"6","(-6675,2900)","0","mstr_standard","I347";
;
CDS_LIB"mstr_standard"
BODY_TYPE"PLUMBING"
HDL_TAP"TRUE";
"B \NAC \NWC"8;
"S \NAC"
BN"0"22;
%"TAP"
"6","(-6525,2750)","0","mstr_standard","I348";
;
CDS_LIB"mstr_standard"
BODY_TYPE"PLUMBING"
HDL_TAP"TRUE";
"B \NAC \NWC"7;
"S \NAC"
BN"2"23;
%"TAP"
"6","(-6525,2650)","0","standard","I349";
;
CDS_LIB"standard"
BODY_TYPE"PLUMBING"
HDL_TAP"TRUE";
"B \NAC \NWC"7;
"S \NAC"
BN"3"21;
%"TAP"
"6","(-6675,2700)","0","standard","I350";
;
CDS_LIB"standard"
BODY_TYPE"PLUMBING"
HDL_TAP"TRUE";
"B \NAC \NWC"8;
"S \NAC"
BN"2"18;
%"TAP"
"6","(-6675,2800)","0","mstr_standard","I351";
;
CDS_LIB"mstr_standard"
BODY_TYPE"PLUMBING"
HDL_TAP"TRUE";
"B \NAC \NWC"8;
"S \NAC"
BN"1"20;
%"TAP"
"6","(-6675,2600)","0","standard","I352";
;
CDS_LIB"standard"
BODY_TYPE"PLUMBING"
HDL_TAP"TRUE";
"B \NAC \NWC"8;
"S \NAC"
BN"3"16;
%"TAP"
"6","(-6525,2550)","0","standard","I353";
;
CDS_LIB"standard"
BODY_TYPE"PLUMBING"
HDL_TAP"TRUE";
"B \NAC \NWC"7;
"S \NAC"
BN"4"19;
%"TAP"
"6","(-6525,2450)","0","standard","I354";
;
CDS_LIB"standard"
BODY_TYPE"PLUMBING"
HDL_TAP"TRUE";
"B \NAC \NWC"7;
"S \NAC"
BN"5"17;
%"TAP"
"6","(-6525,2350)","0","standard","I355";
;
CDS_LIB"standard"
BODY_TYPE"PLUMBING"
HDL_TAP"TRUE";
"B \NAC \NWC"7;
"S \NAC"
BN"6"15;
%"TAP"
"6","(-6675,2500)","0","standard","I356";
;
CDS_LIB"standard"
BODY_TYPE"PLUMBING"
HDL_TAP"TRUE";
"B \NAC \NWC"8;
"S \NAC"
BN"4"14;
%"TAP"
"6","(-6675,2400)","0","standard","I357";
;
CDS_LIB"standard"
BODY_TYPE"PLUMBING"
HDL_TAP"TRUE";
"B \NAC \NWC"8;
"S \NAC"
BN"5"12;
%"TAP"
"6","(-6525,2250)","0","standard","I358";
;
CDS_LIB"standard"
BODY_TYPE"PLUMBING"
HDL_TAP"TRUE";
"B \NAC \NWC"7;
"S \NAC"
BN"7"13;
%"TAP"
"6","(-6525,2150)","0","standard","I359";
;
CDS_LIB"standard"
BODY_TYPE"PLUMBING"
HDL_TAP"TRUE";
"B \NAC \NWC"7;
"S \NAC"
BN"8"34;
%"TAP"
"6","(-6525,2050)","0","standard","I360";
;
CDS_LIB"standard"
BODY_TYPE"PLUMBING"
HDL_TAP"TRUE";
"B \NAC \NWC"7;
"S \NAC"
BN"9"35;
%"TAP"
"6","(-6675,2200)","0","standard","I361";
;
CDS_LIB"standard"
BODY_TYPE"PLUMBING"
HDL_TAP"TRUE";
"B \NAC \NWC"8;
"S \NAC"
BN"7"10;
%"TAP"
"6","(-6675,2300)","0","standard","I362";
;
CDS_LIB"standard"
BODY_TYPE"PLUMBING"
HDL_TAP"TRUE";
"B \NAC \NWC"8;
"S \NAC"
BN"6"11;
%"TAP"
"6","(-6675,2100)","0","standard","I363";
;
CDS_LIB"standard"
BODY_TYPE"PLUMBING"
HDL_TAP"TRUE";
"B \NAC \NWC"8;
"S \NAC"
BN"8"26;
%"TAP"
"6","(-6525,1950)","0","standard","I366";
;
CDS_LIB"standard"
BODY_TYPE"PLUMBING"
HDL_TAP"TRUE";
"B \NAC \NWC"7;
"S \NAC"
BN"10"36;
%"TAP"
"6","(-6525,1850)","0","standard","I367";
;
CDS_LIB"standard"
BODY_TYPE"PLUMBING"
HDL_TAP"TRUE";
"B \NAC \NWC"7;
"S \NAC"
BN"11"37;
%"TAP"
"6","(-6675,2000)","0","standard","I368";
;
CDS_LIB"standard"
BODY_TYPE"PLUMBING"
HDL_TAP"TRUE";
"B \NAC \NWC"8;
"S \NAC"
BN"9"27;
%"TAP"
"6","(-6675,1900)","0","standard","I369";
;
CDS_LIB"standard"
BODY_TYPE"PLUMBING"
HDL_TAP"TRUE";
"B \NAC \NWC"8;
"S \NAC"
BN"10"28;
%"TAP"
"6","(-6675,1800)","0","standard","I370";
;
CDS_LIB"standard"
BODY_TYPE"PLUMBING"
HDL_TAP"TRUE";
"B \NAC \NWC"8;
"S \NAC"
BN"11"29;
%"TAP"
"6","(-6525,1750)","0","standard","I371";
;
CDS_LIB"standard"
BODY_TYPE"PLUMBING"
HDL_TAP"TRUE";
"B \NAC \NWC"7;
"S \NAC"
BN"12"38;
%"TAP"
"6","(-6525,1650)","0","standard","I372";
;
CDS_LIB"standard"
BODY_TYPE"PLUMBING"
HDL_TAP"TRUE";
"B \NAC \NWC"7;
"S \NAC"
BN"13"39;
%"TAP"
"6","(-6525,1550)","0","standard","I373";
;
CDS_LIB"standard"
BODY_TYPE"PLUMBING"
HDL_TAP"TRUE";
"B \NAC \NWC"7;
"S \NAC"
BN"14"40;
%"TAP"
"6","(-6675,1700)","0","standard","I374";
;
CDS_LIB"standard"
BODY_TYPE"PLUMBING"
HDL_TAP"TRUE";
"B \NAC \NWC"8;
"S \NAC"
BN"12"30;
%"TAP"
"6","(-6675,1600)","0","standard","I375";
;
CDS_LIB"standard"
BODY_TYPE"PLUMBING"
HDL_TAP"TRUE";
"B \NAC \NWC"8;
"S \NAC"
BN"13"31;
%"TAP"
"6","(-6525,1450)","0","standard","I376";
;
CDS_LIB"standard"
BODY_TYPE"PLUMBING"
HDL_TAP"TRUE";
"B \NAC \NWC"7;
"S \NAC"
BN"15"41;
%"TAP"
"6","(-6675,1400)","0","standard","I377";
;
CDS_LIB"standard"
BODY_TYPE"PLUMBING"
HDL_TAP"TRUE";
"B \NAC \NWC"8;
"S \NAC"
BN"15"33;
%"TAP"
"6","(-6675,1500)","0","standard","I378";
;
CDS_LIB"standard"
BODY_TYPE"PLUMBING"
HDL_TAP"TRUE";
"B \NAC \NWC"8;
"S \NAC"
BN"14"32;
END.
